(kicad_pcb
	(version 20260206)
	(generator "pcbnew")
	(generator_version "10.0")
	(general
		(thickness 1.6)
		(legacy_teardrops no)
	)
	(paper "A4")
	(title_block
		(title "Wiwynn_Tioga_Pass_MB.brd")
		(comment 1 "Tioga Pass / footprints 3586-3593 of 4770")
	)
	(layers
		(0 "F.Cu" signal "TOP")
		(4 "In1.Cu" signal "L2GND")
		(6 "In2.Cu" signal "L3")
		(8 "In3.Cu" signal "L4GND")
		(10 "In4.Cu" signal "L5")
		(12 "In5.Cu" signal "L6GND")
		(14 "In6.Cu" signal "L7VCC")
		(16 "In7.Cu" signal "L8VCC")
		(18 "In8.Cu" signal "L9GND")
		(20 "In9.Cu" signal "L10")
		(22 "In10.Cu" signal "L11GND")
		(24 "In11.Cu" signal "L12")
		(26 "In12.Cu" signal "L13GND")
		(2 "B.Cu" signal "BOTTOM")
		(9 "F.Adhes" user "F.Adhesive")
		(11 "B.Adhes" user "B.Adhesive")
		(13 "F.Paste" user "Package Geometry/Pastemask Top")
		(15 "B.Paste" user "Package Geometry/Pastemask Bottom")
		(5 "F.SilkS" user "Ref Des/Silkscreen Top")
		(7 "B.SilkS" user "Ref Des/Silkscreen Bottom")
		(1 "F.Mask" user "Board Geometry/Soldermask Top")
		(3 "B.Mask" user "Board Geometry/Soldermask Bottom")
		(17 "Dwgs.User" user "User.Drawings")
		(19 "Cmts.User" user "User.Comments")
		(21 "Eco1.User" user "User.Eco1")
		(23 "Eco2.User" user "User.Eco2")
		(25 "Edge.Cuts" user "Board Geometry/Outline")
		(27 "Margin" user)
		(31 "F.CrtYd" user "Package Geometry/Place Bound Top")
		(29 "B.CrtYd" user "Package Geometry/Place Bound Bottom")
		(35 "F.Fab" user "Ref Des/Assembly Top")
		(33 "B.Fab" user "Ref Des/Assembly Bottom")
	)
	(footprint ""
		(layer "B.Cu")
		(at 482.132894 -17.067022 90)
		(property "Reference" "R9G3"
			(at 0 0 90)
			(layer "B.SilkS")
			(hide yes)
			(effects
				(font
					(size 1.27 1.27)
				)
				(justify mirror)
			)
		)
		(property "Value" ""
			(at 0 0 90)
			(layer "B.Fab")
			(effects
				(font
					(size 1.27 1.27)
				)
				(justify mirror)
			)
		)
		(duplicate_pad_numbers_are_jumpers no)
		(fp_poly
			(pts
				(xy 0.2794 -0.1016) (xy -0.2794 -0.1016) (xy -0.2794 0.9906) (xy 0.2794 0.9906)
			)
			(stroke
				(width 0)
				(type default)
			)
			(fill no)
			(layer "B.CrtYd")
		)
		(fp_line
			(start 0.2794 -0.1016)
			(end 0.2794 0.9906)
			(stroke
				(width 0.1)
				(type default)
			)
			(layer "B.Fab")
		)
		(fp_line
			(start -0.2794 -0.1016)
			(end 0.2794 -0.1016)
			(stroke
				(width 0.1)
				(type default)
			)
			(layer "B.Fab")
		)
		(fp_line
			(start 0.2794 0.9906)
			(end -0.2794 0.9906)
			(stroke
				(width 0.1)
				(type default)
			)
			(layer "B.Fab")
		)
		(fp_line
			(start -0.2794 0.9906)
			(end -0.2794 -0.1016)
			(stroke
				(width 0.1)
				(type default)
			)
			(layer "B.Fab")
		)
		(pad "1" smd rect
			(at 0 0 270)
			(size 0.508 0.508)
			(layers "B.Cu" "B.Mask" "B.Paste")
			(net "LED_LAN_0_R_N")
		)
		(pad "2" smd rect
			(at 0 0.889 270)
			(size 0.508 0.508)
			(layers "B.Cu" "B.Mask" "B.Paste")
			(net "LED_LAN_0_N")
		)
		(zone
			(layer "B.Cu")
			(hatch none 0.5)
			(connect_pads
				(clearance 0)
			)
			(min_thickness 0.25)
			(keepout
				(tracks allowed)
				(vias not_allowed)
				(pads allowed)
				(copperpour not_allowed)
				(footprints allowed)
			)
			(placement
				(enabled no)
				(sheetname "")
			)
			(fill
				(thermal_gap 0.5)
				(thermal_bridge_width 0.5)
				(island_removal_mode 0)
			)
			(polygon
				(pts
					(xy 482.386894 -17.321022) (xy 482.386894 -16.813022) (xy 482.767894 -16.813022) (xy 482.767894 -17.321022)
				)
			)
		)
		(zone
			(layer "B.Cu")
			(hatch none 0.5)
			(connect_pads
				(clearance 0)
			)
			(min_thickness 0.25)
			(keepout
				(tracks not_allowed)
				(vias allowed)
				(pads allowed)
				(copperpour not_allowed)
				(footprints allowed)
			)
			(placement
				(enabled no)
				(sheetname "")
			)
			(fill
				(thermal_gap 0.5)
				(thermal_bridge_width 0.5)
				(island_removal_mode 0)
			)
			(polygon
				(pts
					(xy 482.767894 -17.321022) (xy 482.767894 -16.813022) (xy 482.386894 -16.813022) (xy 482.386894 -17.321022)
				)
			)
		)
	)
	(footprint ""
		(layer "B.Cu")
		(at 105.636568 3.81 90)
		(property "Reference" "C8U11"
			(at 0 0 90)
			(layer "B.SilkS")
			(hide yes)
			(effects
				(font
					(size 1.27 1.27)
				)
				(justify mirror)
			)
		)
		(property "Value" ""
			(at 0 0 90)
			(layer "B.Fab")
			(effects
				(font
					(size 1.27 1.27)
				)
				(justify mirror)
			)
		)
		(duplicate_pad_numbers_are_jumpers no)
		(fp_poly
			(pts
				(xy 0.7239 -0.2159) (xy -0.7239 -0.2159) (xy -0.7239 1.9939) (xy 0.7239 1.9939)
			)
			(stroke
				(width 0)
				(type default)
			)
			(fill no)
			(layer "B.CrtYd")
		)
		(fp_line
			(start 0.7239 -0.2159)
			(end 0.7239 1.9939)
			(stroke
				(width 0.1)
				(type default)
			)
			(layer "B.Fab")
		)
		(fp_line
			(start -0.7239 -0.2159)
			(end 0.7239 -0.2159)
			(stroke
				(width 0.1)
				(type default)
			)
			(layer "B.Fab")
		)
		(fp_line
			(start 0.7239 1.9939)
			(end -0.7239 1.9939)
			(stroke
				(width 0.1)
				(type default)
			)
			(layer "B.Fab")
		)
		(fp_line
			(start -0.7239 1.9939)
			(end -0.7239 -0.2159)
			(stroke
				(width 0.1)
				(type default)
			)
			(layer "B.Fab")
		)
		(pad "1" smd rect
			(at 0 0 270)
			(size 1.27 1.016)
			(layers "B.Cu" "B.Mask" "B.Paste")
			(net "PVDDQ_GHJ")
		)
		(pad "2" smd rect
			(at 0 1.778 270)
			(size 1.27 1.016)
			(layers "B.Cu" "B.Mask" "B.Paste")
			(net "GND")
		)
		(zone
			(layer "B.Cu")
			(hatch none 0.5)
			(connect_pads
				(clearance 0)
			)
			(min_thickness 0.25)
			(keepout
				(tracks not_allowed)
				(vias allowed)
				(pads allowed)
				(copperpour not_allowed)
				(footprints allowed)
			)
			(placement
				(enabled no)
				(sheetname "")
			)
			(fill
				(thermal_gap 0.5)
				(thermal_bridge_width 0.5)
				(island_removal_mode 0)
			)
			(polygon
				(pts
					(xy 106.144568 3.175) (xy 106.144568 4.445) (xy 106.906568 4.445) (xy 106.906568 3.175)
				)
			)
		)
	)
	(footprint ""
		(layer "B.Cu")
		(at 413.922972 -31.805372)
		(property "Reference" "FB2T7"
			(at 0 0 0)
			(layer "B.SilkS")
			(hide yes)
			(effects
				(font
					(size 1.27 1.27)
				)
				(justify mirror)
			)
		)
		(property "Value" "*"
			(at -0.0254 -2.8829 0)
			(unlocked yes)
			(layer "B.Fab")
			(hide yes)
			(effects
				(font
					(size 1.27 1.016)
					(thickness 0.1524)
				)
				(justify mirror)
			)
		)
		(property "Device Type" "HCB1608KF-800T30-GP_DISCRET-G9A"
			(at -0.0254 -4.4069 0)
			(unlocked yes)
			(layer "B.Fab")
			(hide yes)
			(effects
				(font
					(size 1.27 1.016)
					(thickness 0.1524)
				)
				(justify mirror)
			)
		)
		(duplicate_pad_numbers_are_jumpers no)
		(fp_line
			(start -0.254 0)
			(end 0.254 0)
			(stroke
				(width 0.2032)
				(type default)
			)
			(layer "B.SilkS")
		)
		(fp_rect
			(start 0.5842 1.3335)
			(end -0.5842 -1.3335)
			(stroke
				(width 0)
				(type default)
			)
			(fill no)
			(layer "B.CrtYd")
		)
		(fp_rect
			(start 0.5842 1.3335)
			(end -0.5842 -1.3335)
			(stroke
				(width 0)
				(type default)
			)
			(fill no)
			(layer "B.Fab")
		)
		(pad "1" smd custom
			(at 0 -0.762 180)
			(size 0.2159 0.2159)
			(layers "B.Cu" "B.Mask" "B.Paste")
			(net "P1V15_AUX_BMC")
			(options
				(clearance outline)
				(anchor circle)
			)
			(primitives
				(gr_poly
					(pts
						(arc
							(start -0.3302 0.4318)
							(mid -0.402042 0.402042)
							(end -0.4318 0.3302)
						)
						(arc
							(start -0.4318 -0.3302)
							(mid -0.402042 -0.402042)
							(end -0.3302 -0.4318)
						)
						(arc
							(start 0.3302 -0.4318)
							(mid 0.402042 -0.402042)
							(end 0.4318 -0.3302)
						)
						(arc
							(start 0.4318 0.3302)
							(mid 0.402042 0.402042)
							(end 0.3302 0.4318)
						)
					)
					(width 0)
					(fill yes)
				)
			)
		)
		(pad "2" smd custom
			(at 0 0.762 180)
			(size 0.2159 0.2159)
			(layers "B.Cu" "B.Mask" "B.Paste")
			(net "VCC_A_1V1")
			(options
				(clearance outline)
				(anchor circle)
			)
			(primitives
				(gr_poly
					(pts
						(arc
							(start -0.3302 0.4318)
							(mid -0.402042 0.402042)
							(end -0.4318 0.3302)
						)
						(arc
							(start -0.4318 -0.3302)
							(mid -0.402042 -0.402042)
							(end -0.3302 -0.4318)
						)
						(arc
							(start 0.3302 -0.4318)
							(mid 0.402042 -0.402042)
							(end 0.4318 -0.3302)
						)
						(arc
							(start 0.4318 0.3302)
							(mid 0.402042 0.402042)
							(end 0.3302 0.4318)
						)
					)
					(width 0)
					(fill yes)
				)
			)
		)
	)
	(footprint ""
		(layer "B.Cu")
		(at 352.305874 -24.727916 90)
		(property "Reference" "C22W10"
			(at 0 0 90)
			(layer "B.SilkS")
			(hide yes)
			(effects
				(font
					(size 1.27 1.27)
				)
				(justify mirror)
			)
		)
		(property "Value" "*"
			(at 0.0762 -6.2357 90)
			(unlocked yes)
			(layer "B.Fab")
			(hide yes)
			(effects
				(font
					(size 1.27 1.016)
					(thickness 0.1524)
				)
				(justify mirror)
			)
		)
		(property "Device Type" "SC22U16V5MX-4-GP_SMD-BCG5-SC22A"
			(at 0.0762 -8.2677 90)
			(unlocked yes)
			(layer "B.Fab")
			(hide yes)
			(effects
				(font
					(size 1.27 1.016)
					(thickness 0.1524)
				)
				(justify mirror)
			)
		)
		(duplicate_pad_numbers_are_jumpers no)
		(fp_line
			(start -0.635 0)
			(end 0.635 0)
			(stroke
				(width 0.508)
				(type default)
			)
			(layer "B.SilkS")
		)
		(fp_rect
			(start 0.9652 1.778)
			(end -0.9652 -1.778)
			(stroke
				(width 0)
				(type default)
			)
			(fill no)
			(layer "B.CrtYd")
		)
		(fp_poly
			(pts
				(xy 0.9652 -1.778) (xy -0.9652 -1.778) (xy -0.9652 1.778) (xy 0.9652 1.778)
			)
			(stroke
				(width 0)
				(type default)
			)
			(fill no)
			(layer "B.Fab")
		)
		(pad "1" smd rect
			(at 0 -0.9652 270)
			(size 1.397 1.143)
			(layers "B.Cu" "B.Mask" "B.Paste")
			(net "VR_FET_SW_P12V_STBY_PVPP_ABC")
		)
		(pad "2" smd rect
			(at 0 0.9652 270)
			(size 1.397 1.143)
			(layers "B.Cu" "B.Mask" "B.Paste")
			(net "GND")
		)
	)
	(footprint ""
		(layer "B.Cu")
		(at 453.2122 -52.330858)
		(property "Reference" "C1R8"
			(at 0 0 0)
			(layer "B.SilkS")
			(hide yes)
			(effects
				(font
					(size 1.27 1.27)
				)
				(justify mirror)
			)
		)
		(property "Value" ""
			(at 0 0 0)
			(layer "B.Fab")
			(effects
				(font
					(size 1.27 1.27)
				)
				(justify mirror)
			)
		)
		(duplicate_pad_numbers_are_jumpers no)
		(fp_poly
			(pts
				(xy -0.3048 -0.1016) (xy -0.3048 0.9906) (xy 0.3048 0.9906) (xy 0.3048 -0.1016)
			)
			(stroke
				(width 0)
				(type default)
			)
			(fill no)
			(layer "B.CrtYd")
		)
		(fp_line
			(start -0.3048 -0.1016)
			(end 0.3048 -0.1016)
			(stroke
				(width 0.1)
				(type default)
			)
			(layer "B.Fab")
		)
		(fp_line
			(start -0.3048 0.9906)
			(end -0.3048 -0.1016)
			(stroke
				(width 0.1)
				(type default)
			)
			(layer "B.Fab")
		)
		(fp_line
			(start 0.3048 -0.1016)
			(end 0.3048 0.9906)
			(stroke
				(width 0.1)
				(type default)
			)
			(layer "B.Fab")
		)
		(fp_line
			(start 0.3048 0.9906)
			(end -0.3048 0.9906)
			(stroke
				(width 0.1)
				(type default)
			)
			(layer "B.Fab")
		)
		(pad "1" smd rect
			(at 0 0 180)
			(size 0.508 0.508)
			(layers "B.Cu" "B.Mask" "B.Paste")
			(net "P3E_CPU0_PE3_OCP_TXP<3>")
		)
		(pad "2" smd rect
			(at 0 0.889 180)
			(size 0.508 0.508)
			(layers "B.Cu" "B.Mask" "B.Paste")
			(net "P3E_OCP_CPU0_PE3_C_TXP<3>")
		)
		(zone
			(layer "B.Cu")
			(hatch none 0.5)
			(connect_pads
				(clearance 0)
			)
			(min_thickness 0.25)
			(keepout
				(tracks allowed)
				(vias not_allowed)
				(pads allowed)
				(copperpour not_allowed)
				(footprints allowed)
			)
			(placement
				(enabled no)
				(sheetname "")
			)
			(fill
				(thermal_gap 0.5)
				(thermal_bridge_width 0.5)
				(island_removal_mode 0)
			)
			(polygon
				(pts
					(xy 453.4662 -52.076858) (xy 452.9582 -52.076858) (xy 452.9582 -51.695858) (xy 453.4662 -51.695858)
				)
			)
		)
	)
	(footprint ""
		(layer "B.Cu")
		(at 168.529 -65.405)
		(property "Reference" "RF14"
			(at 0.8382 -0.67818 0)
			(unlocked yes)
			(layer "B.SilkS")
			(effects
				(font
					(size 0.4064 0.254)
					(thickness 0.1524)
				)
				(justify left mirror)
			)
		)
		(property "Value" ""
			(at 0 0 0)
			(layer "B.Fab")
			(effects
				(font
					(size 1.27 1.27)
				)
				(justify mirror)
			)
		)
		(duplicate_pad_numbers_are_jumpers no)
		(fp_poly
			(pts
				(xy 0.2794 -0.1016) (xy -0.2794 -0.1016) (xy -0.2794 0.9906) (xy 0.2794 0.9906)
			)
			(stroke
				(width 0)
				(type default)
			)
			(fill no)
			(layer "B.CrtYd")
		)
		(fp_line
			(start -0.2794 -0.1016)
			(end 0.2794 -0.1016)
			(stroke
				(width 0.1)
				(type default)
			)
			(layer "B.Fab")
		)
		(fp_line
			(start -0.2794 0.9906)
			(end -0.2794 -0.1016)
			(stroke
				(width 0.1)
				(type default)
			)
			(layer "B.Fab")
		)
		(fp_line
			(start 0.2794 -0.1016)
			(end 0.2794 0.9906)
			(stroke
				(width 0.1)
				(type default)
			)
			(layer "B.Fab")
		)
		(fp_line
			(start 0.2794 0.9906)
			(end -0.2794 0.9906)
			(stroke
				(width 0.1)
				(type default)
			)
			(layer "B.Fab")
		)
		(pad "1" smd rect
			(at 0 0 180)
			(size 0.508 0.508)
			(layers "B.Cu" "B.Mask" "B.Paste")
			(net "VR_PVCCIO_CPU1_AIREF1")
		)
		(pad "2" smd rect
			(at 0 0.889 180)
			(size 0.508 0.508)
			(layers "B.Cu" "B.Mask" "B.Paste")
			(net "ISENSE_PVCCIO_CPU1_PH1_IMON")
		)
		(zone
			(layer "B.Cu")
			(hatch none 0.5)
			(connect_pads
				(clearance 0)
			)
			(min_thickness 0.25)
			(keepout
				(tracks allowed)
				(vias not_allowed)
				(pads allowed)
				(copperpour not_allowed)
				(footprints allowed)
			)
			(placement
				(enabled no)
				(sheetname "")
			)
			(fill
				(thermal_gap 0.5)
				(thermal_bridge_width 0.5)
				(island_removal_mode 0)
			)
			(polygon
				(pts
					(xy 168.783 -65.151) (xy 168.275 -65.151) (xy 168.275 -64.77) (xy 168.783 -64.77)
				)
			)
		)
		(zone
			(layer "B.Cu")
			(hatch none 0.5)
			(connect_pads
				(clearance 0)
			)
			(min_thickness 0.25)
			(keepout
				(tracks not_allowed)
				(vias allowed)
				(pads allowed)
				(copperpour not_allowed)
				(footprints allowed)
			)
			(placement
				(enabled no)
				(sheetname "")
			)
			(fill
				(thermal_gap 0.5)
				(thermal_bridge_width 0.5)
				(island_removal_mode 0)
			)
			(polygon
				(pts
					(xy 168.783 -64.77) (xy 168.275 -64.77) (xy 168.275 -65.151) (xy 168.783 -65.151)
				)
			)
		)
	)
	(footprint ""
		(layer "B.Cu")
		(at 369.443 -113.792 -90)
		(property "Reference" "C3M40"
			(at 0 0 90)
			(layer "B.SilkS")
			(hide yes)
			(effects
				(font
					(size 1.27 1.27)
				)
				(justify mirror)
			)
		)
		(property "Value" ""
			(at 0 0 90)
			(layer "B.Fab")
			(effects
				(font
					(size 1.27 1.27)
				)
				(justify mirror)
			)
		)
		(duplicate_pad_numbers_are_jumpers no)
		(fp_poly
			(pts
				(xy -0.3048 -0.1016) (xy -0.3048 0.9906) (xy 0.3048 0.9906) (xy 0.3048 -0.1016)
			)
			(stroke
				(width 0)
				(type default)
			)
			(fill no)
			(layer "B.CrtYd")
		)
		(fp_line
			(start -0.3048 0.9906)
			(end -0.3048 -0.1016)
			(stroke
				(width 0.1)
				(type default)
			)
			(layer "B.Fab")
		)
		(fp_line
			(start 0.3048 0.9906)
			(end -0.3048 0.9906)
			(stroke
				(width 0.1)
				(type default)
			)
			(layer "B.Fab")
		)
		(fp_line
			(start -0.3048 -0.1016)
			(end 0.3048 -0.1016)
			(stroke
				(width 0.1)
				(type default)
			)
			(layer "B.Fab")
		)
		(fp_line
			(start 0.3048 -0.1016)
			(end 0.3048 0.9906)
			(stroke
				(width 0.1)
				(type default)
			)
			(layer "B.Fab")
		)
		(pad "1" smd rect
			(at 0 0 90)
			(size 0.508 0.508)
			(layers "B.Cu" "B.Mask" "B.Paste")
			(net "DMI_CPU0_PCH_RX_DP<0>")
		)
		(pad "2" smd rect
			(at 0 0.889 90)
			(size 0.508 0.508)
			(layers "B.Cu" "B.Mask" "B.Paste")
			(net "DMI_CPU0_PCH_RX_C_DP<0>")
		)
		(zone
			(layer "B.Cu")
			(hatch none 0.5)
			(connect_pads
				(clearance 0)
			)
			(min_thickness 0.25)
			(keepout
				(tracks not_allowed)
				(vias allowed)
				(pads allowed)
				(copperpour not_allowed)
				(footprints allowed)
			)
			(placement
				(enabled no)
				(sheetname "")
			)
			(fill
				(thermal_gap 0.5)
				(thermal_bridge_width 0.5)
				(island_removal_mode 0)
			)
			(polygon
				(pts
					(xy 368.808 -113.538) (xy 368.808 -114.046) (xy 369.189 -114.046) (xy 369.189 -113.538)
				)
			)
		)
		(zone
			(layer "B.Cu")
			(hatch none 0.5)
			(connect_pads
				(clearance 0)
			)
			(min_thickness 0.25)
			(keepout
				(tracks allowed)
				(vias not_allowed)
				(pads allowed)
				(copperpour not_allowed)
				(footprints allowed)
			)
			(placement
				(enabled no)
				(sheetname "")
			)
			(fill
				(thermal_gap 0.5)
				(thermal_bridge_width 0.5)
				(island_removal_mode 0)
			)
			(polygon
				(pts
					(xy 369.189 -113.538) (xy 369.189 -114.046) (xy 368.808 -114.046) (xy 368.808 -113.538)
				)
			)
		)
	)
	(footprint ""
		(layer "B.Cu")
		(at 422.8465 -4.191 -90)
		(property "Reference" "R3P44"
			(at 0 0 90)
			(layer "B.SilkS")
			(hide yes)
			(effects
				(font
					(size 1.27 1.27)
				)
				(justify mirror)
			)
		)
		(property "Value" ""
			(at 0 0 90)
			(layer "B.Fab")
			(effects
				(font
					(size 1.27 1.27)
				)
				(justify mirror)
			)
		)
		(duplicate_pad_numbers_are_jumpers no)
		(fp_rect
			(start 0.2794 -0.1016)
			(end -0.2794 0.9906)
			(stroke
				(width 0)
				(type default)
			)
			(fill no)
			(layer "B.CrtYd")
		)
		(fp_line
			(start -0.2794 0.9906)
			(end -0.2794 -0.1016)
			(stroke
				(width 0.1)
				(type default)
			)
			(layer "B.Fab")
		)
		(fp_line
			(start 0.2794 0.9906)
			(end -0.2794 0.9906)
			(stroke
				(width 0.1)
				(type default)
			)
			(layer "B.Fab")
		)
		(fp_line
			(start -0.2794 -0.1016)
			(end 0.2794 -0.1016)
			(stroke
				(width 0.1)
				(type default)
			)
			(layer "B.Fab")
		)
		(fp_line
			(start 0.2794 -0.1016)
			(end 0.2794 0.9906)
			(stroke
				(width 0.1)
				(type default)
			)
			(layer "B.Fab")
		)
		(pad "1" smd rect
			(at 0 0 90)
			(size 0.508 0.508)
			(layers "B.Cu" "B.Mask" "B.Paste")
			(net "P3V3_STBY")
		)
		(pad "2" smd rect
			(at 0 0.889 90)
			(size 0.508 0.508)
			(layers "B.Cu" "B.Mask" "B.Paste")
			(net "PWRGD_DSW_PWROK")
		)
		(zone
			(layer "B.Cu")
			(hatch none 0.5)
			(connect_pads
				(clearance 0)
			)
			(min_thickness 0.25)
			(keepout
				(tracks allowed)
				(vias not_allowed)
				(pads allowed)
				(copperpour not_allowed)
				(footprints allowed)
			)
			(placement
				(enabled no)
				(sheetname "")
			)
			(fill
				(thermal_gap 0.5)
				(thermal_bridge_width 0.5)
				(island_removal_mode 0)
			)
			(polygon
				(pts
					(xy 422.5925 -3.937) (xy 422.5925 -4.445) (xy 422.2115 -4.445) (xy 422.2115 -3.937)
				)
			)
		)
		(zone
			(layer "B.Cu")
			(hatch none 0.5)
			(connect_pads
				(clearance 0)
			)
			(min_thickness 0.25)
			(keepout
				(tracks not_allowed)
				(vias allowed)
				(pads allowed)
				(copperpour not_allowed)
				(footprints allowed)
			)
			(placement
				(enabled no)
				(sheetname "")
			)
			(fill
				(thermal_gap 0.5)
				(thermal_bridge_width 0.5)
				(island_removal_mode 0)
			)
			(polygon
				(pts
					(xy 422.5925 -3.937) (xy 422.5925 -4.445) (xy 422.2115 -4.445) (xy 422.2115 -3.937)
				)
			)
		)
	)
)
